(kicad_pcb
	(version 20260206)
	(generator "pcbnew")
	(generator_version "10.0")
	(general
		(thickness 1.6)
		(legacy_teardrops no)
	)
	(paper "A4")
	(title_block
		(title "04192023_DAF0TMB3IC0_F0TG_MB_C_brd_V02_OCP.brd")
		(comment 1 "Grand Teton / footprints 834-839 of 8354")
	)
	(layers
		(0 "F.Cu" signal "TOP")
		(4 "In1.Cu" signal "GND")
		(6 "In2.Cu" signal "IN1")
		(8 "In3.Cu" signal "GND1")
		(10 "In4.Cu" signal "IN2")
		(12 "In5.Cu" signal "GND2")
		(14 "In6.Cu" signal "IN3")
		(16 "In7.Cu" signal "GND3")
		(18 "In8.Cu" signal "VCC")
		(20 "In9.Cu" signal "VCC1")
		(22 "In10.Cu" signal "GND4")
		(24 "In11.Cu" signal "IN4")
		(26 "In12.Cu" signal "GND5")
		(28 "In13.Cu" signal "IN5")
		(30 "In14.Cu" signal "GND6")
		(32 "In15.Cu" signal "IN6")
		(34 "In16.Cu" signal "GND7")
		(2 "B.Cu" signal "BOTTOM")
		(9 "F.Adhes" user "F.Adhesive")
		(11 "B.Adhes" user "B.Adhesive")
		(13 "F.Paste" user "Package Geometry/Pastemask Top")
		(15 "B.Paste" user "Package Geometry/Pastemask Bottom")
		(5 "F.SilkS" user "Ref Des/Silkscreen Top")
		(7 "B.SilkS" user "Ref Des/Silkscreen Bottom")
		(1 "F.Mask" user "Board Geometry/Soldermask Top")
		(3 "B.Mask" user "Board Geometry/Soldermask Bottom")
		(17 "Dwgs.User" user "User.Drawings")
		(19 "Cmts.User" user "User.Comments")
		(21 "Eco1.User" user "User.Eco1")
		(23 "Eco2.User" user "User.Eco2")
		(25 "Edge.Cuts" user "Board Geometry/Outline")
		(27 "Margin" user)
		(31 "F.CrtYd" user "Package Geometry/Place Bound Top")
		(29 "B.CrtYd" user "Package Geometry/Place Bound Bottom")
		(35 "F.Fab" user "Ref Des/Assembly Top")
		(33 "B.Fab" user "Ref Des/Assembly Bottom")
	)
	(footprint ""
		(layer "F.Cu")
		(at 176.911 -129.377948 90)
		(property "Reference" "R192"
			(at 0 0 90)
			(layer "F.SilkS")
			(hide yes)
			(effects
				(font
					(size 1.27 1.27)
				)
			)
		)
		(property "Value" ""
			(at 0 0 90)
			(layer "F.Fab")
			(effects
				(font
					(size 1.27 1.27)
				)
			)
		)
		(duplicate_pad_numbers_are_jumpers no)
		(fp_line
			(start 0.7874 -0.4064)
			(end 0.7874 0.4064)
			(stroke
				(width 0.1524)
				(type default)
			)
			(layer "F.SilkS")
		)
		(fp_line
			(start -0.7874 -0.4064)
			(end 0.7874 -0.4064)
			(stroke
				(width 0.1524)
				(type default)
			)
			(layer "F.SilkS")
		)
		(fp_line
			(start 0.7874 0.4064)
			(end -0.7874 0.4064)
			(stroke
				(width 0.1524)
				(type default)
			)
			(layer "F.SilkS")
		)
		(fp_line
			(start -0.7874 0.4064)
			(end -0.7874 -0.4064)
			(stroke
				(width 0.1524)
				(type default)
			)
			(layer "F.SilkS")
		)
		(fp_line
			(start -0.12065 -0.305054)
			(end -0.12065 -0.2794)
			(stroke
				(width 0.1)
				(type default)
			)
			(layer "F.Fab")
		)
		(fp_line
			(start -0.67945 -0.305054)
			(end -0.12065 -0.305054)
			(stroke
				(width 0.1)
				(type default)
			)
			(layer "F.Fab")
		)
		(fp_line
			(start 0.67945 -0.3048)
			(end 0.67945 0.3048)
			(stroke
				(width 0.1)
				(type default)
			)
			(layer "F.Fab")
		)
		(fp_line
			(start 0.12065 -0.3048)
			(end 0.67945 -0.3048)
			(stroke
				(width 0.1)
				(type default)
			)
			(layer "F.Fab")
		)
		(fp_line
			(start 0.12065 -0.2794)
			(end 0.12065 -0.3048)
			(stroke
				(width 0.1)
				(type default)
			)
			(layer "F.Fab")
		)
		(fp_line
			(start -0.12065 -0.2794)
			(end 0.12065 -0.2794)
			(stroke
				(width 0.1)
				(type default)
			)
			(layer "F.Fab")
		)
		(fp_line
			(start 0.120396 0.2794)
			(end -0.12065 0.2794)
			(stroke
				(width 0.1)
				(type default)
			)
			(layer "F.Fab")
		)
		(fp_line
			(start -0.12065 0.2794)
			(end -0.12065 0.3048)
			(stroke
				(width 0.1)
				(type default)
			)
			(layer "F.Fab")
		)
		(fp_line
			(start 0.67945 0.3048)
			(end 0.120396 0.3048)
			(stroke
				(width 0.1)
				(type default)
			)
			(layer "F.Fab")
		)
		(fp_line
			(start 0.120396 0.3048)
			(end 0.120396 0.2794)
			(stroke
				(width 0.1)
				(type default)
			)
			(layer "F.Fab")
		)
		(fp_line
			(start -0.12065 0.3048)
			(end -0.67945 0.3048)
			(stroke
				(width 0.1)
				(type default)
			)
			(layer "F.Fab")
		)
		(fp_line
			(start -0.67945 0.3048)
			(end -0.67945 -0.305054)
			(stroke
				(width 0.1)
				(type default)
			)
			(layer "F.Fab")
		)
		(pad "1" smd circle
			(at -0.40005 0 90)
			(size 0 0)
			(layers "F.Cu" "F.Mask" "F.Paste")
			(net "FM_CPU1_SLP_S3_N")
		)
		(pad "2" smd circle
			(at 0.40005 0 90)
			(size 0 0)
			(layers "F.Cu" "F.Mask" "F.Paste")
			(net "CPU1_SLP_S3_N")
		)
	)
	(footprint ""
		(layer "F.Cu")
		(at 324.853046 -99.284536 180)
		(property "Reference" "R1272"
			(at 0 0 180)
			(layer "F.SilkS")
			(hide yes)
			(effects
				(font
					(size 1.27 1.27)
				)
			)
		)
		(property "Value" ""
			(at 0 0 180)
			(layer "F.Fab")
			(effects
				(font
					(size 1.27 1.27)
				)
			)
		)
		(duplicate_pad_numbers_are_jumpers no)
		(fp_line
			(start 0.7874 0.4064)
			(end -0.7874 0.4064)
			(stroke
				(width 0.1524)
				(type default)
			)
			(layer "F.SilkS")
		)
		(fp_line
			(start 0.7874 -0.4064)
			(end 0.7874 0.4064)
			(stroke
				(width 0.1524)
				(type default)
			)
			(layer "F.SilkS")
		)
		(fp_line
			(start -0.7874 0.4064)
			(end -0.7874 -0.4064)
			(stroke
				(width 0.1524)
				(type default)
			)
			(layer "F.SilkS")
		)
		(fp_line
			(start -0.7874 -0.4064)
			(end 0.7874 -0.4064)
			(stroke
				(width 0.1524)
				(type default)
			)
			(layer "F.SilkS")
		)
		(fp_line
			(start 0.67945 0.3048)
			(end 0.120396 0.3048)
			(stroke
				(width 0.1)
				(type default)
			)
			(layer "F.Fab")
		)
		(fp_line
			(start 0.67945 -0.3048)
			(end 0.67945 0.3048)
			(stroke
				(width 0.1)
				(type default)
			)
			(layer "F.Fab")
		)
		(fp_line
			(start 0.12065 -0.2794)
			(end 0.12065 -0.3048)
			(stroke
				(width 0.1)
				(type default)
			)
			(layer "F.Fab")
		)
		(fp_line
			(start 0.12065 -0.3048)
			(end 0.67945 -0.3048)
			(stroke
				(width 0.1)
				(type default)
			)
			(layer "F.Fab")
		)
		(fp_line
			(start 0.120396 0.3048)
			(end 0.120396 0.2794)
			(stroke
				(width 0.1)
				(type default)
			)
			(layer "F.Fab")
		)
		(fp_line
			(start 0.120396 0.2794)
			(end -0.12065 0.2794)
			(stroke
				(width 0.1)
				(type default)
			)
			(layer "F.Fab")
		)
		(fp_line
			(start -0.12065 0.3048)
			(end -0.67945 0.3048)
			(stroke
				(width 0.1)
				(type default)
			)
			(layer "F.Fab")
		)
		(fp_line
			(start -0.12065 0.2794)
			(end -0.12065 0.3048)
			(stroke
				(width 0.1)
				(type default)
			)
			(layer "F.Fab")
		)
		(fp_line
			(start -0.12065 -0.2794)
			(end 0.12065 -0.2794)
			(stroke
				(width 0.1)
				(type default)
			)
			(layer "F.Fab")
		)
		(fp_line
			(start -0.12065 -0.305054)
			(end -0.12065 -0.2794)
			(stroke
				(width 0.1)
				(type default)
			)
			(layer "F.Fab")
		)
		(fp_line
			(start -0.67945 0.3048)
			(end -0.67945 -0.305054)
			(stroke
				(width 0.1)
				(type default)
			)
			(layer "F.Fab")
		)
		(fp_line
			(start -0.67945 -0.305054)
			(end -0.12065 -0.305054)
			(stroke
				(width 0.1)
				(type default)
			)
			(layer "F.Fab")
		)
		(pad "1" smd circle
			(at -0.40005 0 180)
			(size 0 0)
			(layers "F.Cu" "F.Mask" "F.Paste")
			(net "SMB_INA230_8_3V3AUX_SCL_R")
		)
		(pad "2" smd circle
			(at 0.40005 0 180)
			(size 0 0)
			(layers "F.Cu" "F.Mask" "F.Paste")
			(net "SMB_INA230_8_3V3AUX_SCL_R1")
		)
	)
	(footprint ""
		(layer "F.Cu")
		(at 138.617198 -168.577006)
		(property "Reference" "PR163"
			(at 0 0 0)
			(layer "F.SilkS")
			(hide yes)
			(effects
				(font
					(size 1.27 1.27)
				)
			)
		)
		(property "Value" ""
			(at 0 0 0)
			(layer "F.Fab")
			(effects
				(font
					(size 1.27 1.27)
				)
			)
		)
		(duplicate_pad_numbers_are_jumpers no)
		(fp_line
			(start -0.7874 -0.4064)
			(end 0.7874 -0.4064)
			(stroke
				(width 0.1524)
				(type default)
			)
			(layer "F.SilkS")
		)
		(fp_line
			(start -0.7874 0.4064)
			(end -0.7874 -0.4064)
			(stroke
				(width 0.1524)
				(type default)
			)
			(layer "F.SilkS")
		)
		(fp_line
			(start 0.7874 -0.4064)
			(end 0.7874 0.4064)
			(stroke
				(width 0.1524)
				(type default)
			)
			(layer "F.SilkS")
		)
		(fp_line
			(start 0.7874 0.4064)
			(end -0.7874 0.4064)
			(stroke
				(width 0.1524)
				(type default)
			)
			(layer "F.SilkS")
		)
		(fp_line
			(start -0.67945 -0.305054)
			(end -0.12065 -0.305054)
			(stroke
				(width 0.1)
				(type default)
			)
			(layer "F.Fab")
		)
		(fp_line
			(start -0.67945 0.3048)
			(end -0.67945 -0.305054)
			(stroke
				(width 0.1)
				(type default)
			)
			(layer "F.Fab")
		)
		(fp_line
			(start -0.12065 -0.305054)
			(end -0.12065 -0.2794)
			(stroke
				(width 0.1)
				(type default)
			)
			(layer "F.Fab")
		)
		(fp_line
			(start -0.12065 -0.2794)
			(end 0.12065 -0.2794)
			(stroke
				(width 0.1)
				(type default)
			)
			(layer "F.Fab")
		)
		(fp_line
			(start -0.12065 0.2794)
			(end -0.12065 0.3048)
			(stroke
				(width 0.1)
				(type default)
			)
			(layer "F.Fab")
		)
		(fp_line
			(start -0.12065 0.3048)
			(end -0.67945 0.3048)
			(stroke
				(width 0.1)
				(type default)
			)
			(layer "F.Fab")
		)
		(fp_line
			(start 0.120396 0.2794)
			(end -0.12065 0.2794)
			(stroke
				(width 0.1)
				(type default)
			)
			(layer "F.Fab")
		)
		(fp_line
			(start 0.120396 0.3048)
			(end 0.120396 0.2794)
			(stroke
				(width 0.1)
				(type default)
			)
			(layer "F.Fab")
		)
		(fp_line
			(start 0.12065 -0.3048)
			(end 0.67945 -0.3048)
			(stroke
				(width 0.1)
				(type default)
			)
			(layer "F.Fab")
		)
		(fp_line
			(start 0.12065 -0.2794)
			(end 0.12065 -0.3048)
			(stroke
				(width 0.1)
				(type default)
			)
			(layer "F.Fab")
		)
		(fp_line
			(start 0.67945 -0.3048)
			(end 0.67945 0.3048)
			(stroke
				(width 0.1)
				(type default)
			)
			(layer "F.Fab")
		)
		(fp_line
			(start 0.67945 0.3048)
			(end 0.120396 0.3048)
			(stroke
				(width 0.1)
				(type default)
			)
			(layer "F.Fab")
		)
		(pad "1" smd circle
			(at -0.40005 0)
			(size 0 0)
			(layers "F.Cu" "F.Mask" "F.Paste")
			(net "PVDDCR_SOC_P1")
		)
		(pad "2" smd circle
			(at 0.40005 0)
			(size 0 0)
			(layers "F.Cu" "F.Mask" "F.Paste")
			(net "VSENSE_PVDDCR_SOC_P1_DP")
		)
	)
	(footprint ""
		(layer "F.Cu")
		(at 196.708268 -78.42377 180)
		(property "Reference" "R80"
			(at 0 0 180)
			(layer "F.SilkS")
			(hide yes)
			(effects
				(font
					(size 1.27 1.27)
				)
			)
		)
		(property "Value" ""
			(at 0 0 180)
			(layer "F.Fab")
			(effects
				(font
					(size 1.27 1.27)
				)
			)
		)
		(duplicate_pad_numbers_are_jumpers no)
		(fp_line
			(start 0.7874 0.4064)
			(end -0.7874 0.4064)
			(stroke
				(width 0.1524)
				(type default)
			)
			(layer "F.SilkS")
		)
		(fp_line
			(start 0.7874 -0.4064)
			(end 0.7874 0.4064)
			(stroke
				(width 0.1524)
				(type default)
			)
			(layer "F.SilkS")
		)
		(fp_line
			(start -0.7874 0.4064)
			(end -0.7874 -0.4064)
			(stroke
				(width 0.1524)
				(type default)
			)
			(layer "F.SilkS")
		)
		(fp_line
			(start -0.7874 -0.4064)
			(end 0.7874 -0.4064)
			(stroke
				(width 0.1524)
				(type default)
			)
			(layer "F.SilkS")
		)
		(fp_line
			(start 0.67945 0.3048)
			(end 0.120396 0.3048)
			(stroke
				(width 0.1)
				(type default)
			)
			(layer "F.Fab")
		)
		(fp_line
			(start 0.67945 -0.3048)
			(end 0.67945 0.3048)
			(stroke
				(width 0.1)
				(type default)
			)
			(layer "F.Fab")
		)
		(fp_line
			(start 0.12065 -0.2794)
			(end 0.12065 -0.3048)
			(stroke
				(width 0.1)
				(type default)
			)
			(layer "F.Fab")
		)
		(fp_line
			(start 0.12065 -0.3048)
			(end 0.67945 -0.3048)
			(stroke
				(width 0.1)
				(type default)
			)
			(layer "F.Fab")
		)
		(fp_line
			(start 0.120396 0.3048)
			(end 0.120396 0.2794)
			(stroke
				(width 0.1)
				(type default)
			)
			(layer "F.Fab")
		)
		(fp_line
			(start 0.120396 0.2794)
			(end -0.12065 0.2794)
			(stroke
				(width 0.1)
				(type default)
			)
			(layer "F.Fab")
		)
		(fp_line
			(start -0.12065 0.3048)
			(end -0.67945 0.3048)
			(stroke
				(width 0.1)
				(type default)
			)
			(layer "F.Fab")
		)
		(fp_line
			(start -0.12065 0.2794)
			(end -0.12065 0.3048)
			(stroke
				(width 0.1)
				(type default)
			)
			(layer "F.Fab")
		)
		(fp_line
			(start -0.12065 -0.2794)
			(end 0.12065 -0.2794)
			(stroke
				(width 0.1)
				(type default)
			)
			(layer "F.Fab")
		)
		(fp_line
			(start -0.12065 -0.305054)
			(end -0.12065 -0.2794)
			(stroke
				(width 0.1)
				(type default)
			)
			(layer "F.Fab")
		)
		(fp_line
			(start -0.67945 0.3048)
			(end -0.67945 -0.305054)
			(stroke
				(width 0.1)
				(type default)
			)
			(layer "F.Fab")
		)
		(fp_line
			(start -0.67945 -0.305054)
			(end -0.12065 -0.305054)
			(stroke
				(width 0.1)
				(type default)
			)
			(layer "F.Fab")
		)
		(pad "1" smd circle
			(at -0.40005 0 180)
			(size 0 0)
			(layers "F.Cu" "F.Mask" "F.Paste")
			(net "RMII_OCP_BMC_RXD_1")
		)
		(pad "2" smd circle
			(at 0.40005 0 180)
			(size 0 0)
			(layers "F.Cu" "F.Mask" "F.Paste")
			(net "GND")
		)
	)
	(footprint ""
		(layer "F.Cu")
		(at 302.1584 -362.839)
		(property "Reference" "R8056"
			(at 0 0 0)
			(layer "F.SilkS")
			(hide yes)
			(effects
				(font
					(size 1.27 1.27)
				)
			)
		)
		(property "Value" ""
			(at 0 0 0)
			(layer "F.Fab")
			(effects
				(font
					(size 1.27 1.27)
				)
			)
		)
		(duplicate_pad_numbers_are_jumpers no)
		(fp_line
			(start -0.7874 -0.4064)
			(end 0.7874 -0.4064)
			(stroke
				(width 0.1524)
				(type default)
			)
			(layer "F.SilkS")
		)
		(fp_line
			(start -0.7874 0.4064)
			(end -0.7874 -0.4064)
			(stroke
				(width 0.1524)
				(type default)
			)
			(layer "F.SilkS")
		)
		(fp_line
			(start 0.7874 -0.4064)
			(end 0.7874 0.4064)
			(stroke
				(width 0.1524)
				(type default)
			)
			(layer "F.SilkS")
		)
		(fp_line
			(start 0.7874 0.4064)
			(end -0.7874 0.4064)
			(stroke
				(width 0.1524)
				(type default)
			)
			(layer "F.SilkS")
		)
		(fp_line
			(start -0.67945 -0.305054)
			(end -0.12065 -0.305054)
			(stroke
				(width 0.1)
				(type default)
			)
			(layer "F.Fab")
		)
		(fp_line
			(start -0.67945 0.3048)
			(end -0.67945 -0.305054)
			(stroke
				(width 0.1)
				(type default)
			)
			(layer "F.Fab")
		)
		(fp_line
			(start -0.12065 -0.305054)
			(end -0.12065 -0.2794)
			(stroke
				(width 0.1)
				(type default)
			)
			(layer "F.Fab")
		)
		(fp_line
			(start -0.12065 -0.2794)
			(end 0.12065 -0.2794)
			(stroke
				(width 0.1)
				(type default)
			)
			(layer "F.Fab")
		)
		(fp_line
			(start -0.12065 0.2794)
			(end -0.12065 0.3048)
			(stroke
				(width 0.1)
				(type default)
			)
			(layer "F.Fab")
		)
		(fp_line
			(start -0.12065 0.3048)
			(end -0.67945 0.3048)
			(stroke
				(width 0.1)
				(type default)
			)
			(layer "F.Fab")
		)
		(fp_line
			(start 0.120396 0.2794)
			(end -0.12065 0.2794)
			(stroke
				(width 0.1)
				(type default)
			)
			(layer "F.Fab")
		)
		(fp_line
			(start 0.120396 0.3048)
			(end 0.120396 0.2794)
			(stroke
				(width 0.1)
				(type default)
			)
			(layer "F.Fab")
		)
		(fp_line
			(start 0.12065 -0.3048)
			(end 0.67945 -0.3048)
			(stroke
				(width 0.1)
				(type default)
			)
			(layer "F.Fab")
		)
		(fp_line
			(start 0.12065 -0.2794)
			(end 0.12065 -0.3048)
			(stroke
				(width 0.1)
				(type default)
			)
			(layer "F.Fab")
		)
		(fp_line
			(start 0.67945 -0.3048)
			(end 0.67945 0.3048)
			(stroke
				(width 0.1)
				(type default)
			)
			(layer "F.Fab")
		)
		(fp_line
			(start 0.67945 0.3048)
			(end 0.120396 0.3048)
			(stroke
				(width 0.1)
				(type default)
			)
			(layer "F.Fab")
		)
		(pad "1" smd circle
			(at -0.40005 0)
			(size 0 0)
			(layers "F.Cu" "F.Mask" "F.Paste")
			(net "P3V3_AUX")
		)
		(pad "2" smd circle
			(at 0.40005 0)
			(size 0 0)
			(layers "F.Cu" "F.Mask" "F.Paste")
			(net "PWRGD_PVDDCR_CPU1_P0_R")
		)
	)
	(footprint ""
		(layer "F.Cu")
		(at 165.2016 -436.153052)
		(property "Reference" "C1973"
			(at 0 0 0)
			(layer "F.SilkS")
			(hide yes)
			(effects
				(font
					(size 1.27 1.27)
				)
			)
		)
		(property "Value" ""
			(at 0 0 0)
			(layer "F.Fab")
			(effects
				(font
					(size 1.27 1.27)
				)
			)
		)
		(duplicate_pad_numbers_are_jumpers no)
		(fp_line
			(start -0.7874 -0.4064)
			(end 0.7874 -0.4064)
			(stroke
				(width 0.1524)
				(type default)
			)
			(layer "F.SilkS")
		)
		(fp_line
			(start -0.7874 0.4064)
			(end -0.7874 -0.4064)
			(stroke
				(width 0.1524)
				(type default)
			)
			(layer "F.SilkS")
		)
		(fp_line
			(start 0.7874 -0.4064)
			(end 0.7874 0.4064)
			(stroke
				(width 0.1524)
				(type default)
			)
			(layer "F.SilkS")
		)
		(fp_line
			(start 0.7874 0.4064)
			(end -0.7874 0.4064)
			(stroke
				(width 0.1524)
				(type default)
			)
			(layer "F.SilkS")
		)
		(fp_line
			(start -0.67945 -0.305054)
			(end -0.12065 -0.305054)
			(stroke
				(width 0.1)
				(type default)
			)
			(layer "F.Fab")
		)
		(fp_line
			(start -0.67945 0.3048)
			(end -0.67945 -0.305054)
			(stroke
				(width 0.1)
				(type default)
			)
			(layer "F.Fab")
		)
		(fp_line
			(start -0.12065 -0.305054)
			(end -0.12065 -0.2794)
			(stroke
				(width 0.1)
				(type default)
			)
			(layer "F.Fab")
		)
		(fp_line
			(start -0.12065 -0.2794)
			(end 0.12065 -0.2794)
			(stroke
				(width 0.1)
				(type default)
			)
			(layer "F.Fab")
		)
		(fp_line
			(start -0.12065 0.2794)
			(end -0.12065 0.3048)
			(stroke
				(width 0.1)
				(type default)
			)
			(layer "F.Fab")
		)
		(fp_line
			(start -0.12065 0.3048)
			(end -0.67945 0.3048)
			(stroke
				(width 0.1)
				(type default)
			)
			(layer "F.Fab")
		)
		(fp_line
			(start 0.120396 0.2794)
			(end -0.12065 0.2794)
			(stroke
				(width 0.1)
				(type default)
			)
			(layer "F.Fab")
		)
		(fp_line
			(start 0.120396 0.3048)
			(end 0.120396 0.2794)
			(stroke
				(width 0.1)
				(type default)
			)
			(layer "F.Fab")
		)
		(fp_line
			(start 0.12065 -0.3048)
			(end 0.67945 -0.3048)
			(stroke
				(width 0.1)
				(type default)
			)
			(layer "F.Fab")
		)
		(fp_line
			(start 0.12065 -0.2794)
			(end 0.12065 -0.3048)
			(stroke
				(width 0.1)
				(type default)
			)
			(layer "F.Fab")
		)
		(fp_line
			(start 0.67945 -0.3048)
			(end 0.67945 0.3048)
			(stroke
				(width 0.1)
				(type default)
			)
			(layer "F.Fab")
		)
		(fp_line
			(start 0.67945 0.3048)
			(end 0.120396 0.3048)
			(stroke
				(width 0.1)
				(type default)
			)
			(layer "F.Fab")
		)
		(pad "1" smd circle
			(at -0.40005 0)
			(size 0 0)
			(layers "F.Cu" "F.Mask" "F.Paste")
			(net "GPU_BASE_HMC_READY_ISO")
		)
		(pad "2" smd circle
			(at 0.40005 0)
			(size 0 0)
			(layers "F.Cu" "F.Mask" "F.Paste")
			(net "GND")
		)
	)
)
